# T6G (Grand Teton) — schematic netlist excerpt (pin names and nets, part order shuffled) for the footprints in the layout excerpt that follows; sources: Cadence DE-HDL packaged netlist, KiCad conversion of 04192023_DAF0TMB3IC0_F0TG_MB_C_brd_V02_OCP.brd

C979  Q_CAP  1UF 4V 20% X6S  pkg 0201  page 301 : A = P0V9_CPU0_RT2_2A ; B = GND
C1774  Q_CAP  0.1UF 25V 10% X7R  pkg 0402  page 127 : A = FM_SWB_PWRGD_ISO ; B = GND
C2543  Q_CAP  22UF 4V 20% X6S  pkg C0402  page 70 : A = PVDDCR_SOC_P0 ; B = GND

(kicad_pcb
	(version 20260206)
	(generator "pcbnew")
	(generator_version "10.0")
	(general
		(thickness 1.6)
		(legacy_teardrops no)
	)
	(paper "A4")
	(title_block
		(title "04192023_DAF0TMB3IC0_F0TG_MB_C_brd_V02_OCP.brd")
		(comment 1 "Grand Teton / footprints 5093-5095 of 8354")
	)
	(layers
		(0 "F.Cu" signal "TOP")
		(4 "In1.Cu" signal "GND")
		(6 "In2.Cu" signal "IN1")
		(8 "In3.Cu" signal "GND1")
		(10 "In4.Cu" signal "IN2")
		(12 "In5.Cu" signal "GND2")
		(14 "In6.Cu" signal "IN3")
		(16 "In7.Cu" signal "GND3")
		(18 "In8.Cu" signal "VCC")
		(20 "In9.Cu" signal "VCC1")
		(22 "In10.Cu" signal "GND4")
		(24 "In11.Cu" signal "IN4")
		(26 "In12.Cu" signal "GND5")
		(28 "In13.Cu" signal "IN5")
		(30 "In14.Cu" signal "GND6")
		(32 "In15.Cu" signal "IN6")
		(34 "In16.Cu" signal "GND7")
		(2 "B.Cu" signal "BOTTOM")
		(9 "F.Adhes" user "F.Adhesive")
		(11 "B.Adhes" user "B.Adhesive")
		(13 "F.Paste" user "Package Geometry/Pastemask Top")
		(15 "B.Paste" user "Package Geometry/Pastemask Bottom")
		(5 "F.SilkS" user "Ref Des/Silkscreen Top")
		(7 "B.SilkS" user "Ref Des/Silkscreen Bottom")
		(1 "F.Mask" user "Board Geometry/Soldermask Top")
		(3 "B.Mask" user "Board Geometry/Soldermask Bottom")
		(17 "Dwgs.User" user "User.Drawings")
		(19 "Cmts.User" user "User.Comments")
		(21 "Eco1.User" user "User.Eco1")
		(23 "Eco2.User" user "User.Eco2")
		(25 "Edge.Cuts" user "Board Geometry/Outline")
		(27 "Margin" user)
		(31 "F.CrtYd" user "Package Geometry/Place Bound Top")
		(29 "B.CrtYd" user "Package Geometry/Place Bound Bottom")
		(35 "F.Fab" user "Ref Des/Assembly Top")
		(33 "B.Fab" user "Ref Des/Assembly Bottom")
	)
	(footprint ""
		(layer "B.Cu")
		(at 359.833926 -416.923474 180)
		(property "Reference" "C1774"
			(at 0 0 0)
			(layer "B.SilkS")
			(hide yes)
			(effects
				(font
					(size 1.27 1.27)
				)
				(justify mirror)
			)
		)
		(property "Value" ""
			(at 0 0 0)
			(layer "B.Fab")
			(effects
				(font
					(size 1.27 1.27)
				)
				(justify mirror)
			)
		)
		(duplicate_pad_numbers_are_jumpers no)
		(fp_line
			(start 0.7874 0.4064)
			(end 0.7874 -0.4064)
			(stroke
				(width 0.1524)
				(type default)
			)
			(layer "B.SilkS")
		)
		(fp_line
			(start 0.7874 -0.4064)
			(end -0.7874 -0.4064)
			(stroke
				(width 0.1524)
				(type default)
			)
			(layer "B.SilkS")
		)
		(fp_line
			(start -0.7874 0.4064)
			(end 0.7874 0.4064)
			(stroke
				(width 0.1524)
				(type default)
			)
			(layer "B.SilkS")
		)
		(fp_line
			(start -0.7874 -0.4064)
			(end -0.7874 0.4064)
			(stroke
				(width 0.1524)
				(type default)
			)
			(layer "B.SilkS")
		)
		(fp_line
			(start 0.67945 0.3048)
			(end 0.67945 -0.305054)
			(stroke
				(width 0.1)
				(type default)
			)
			(layer "B.Fab")
		)
		(fp_line
			(start 0.67945 -0.305054)
			(end 0.12065 -0.305054)
			(stroke
				(width 0.1)
				(type default)
			)
			(layer "B.Fab")
		)
		(fp_line
			(start 0.12065 0.3048)
			(end 0.67945 0.3048)
			(stroke
				(width 0.1)
				(type default)
			)
			(layer "B.Fab")
		)
		(fp_line
			(start 0.12065 0.2794)
			(end 0.12065 0.3048)
			(stroke
				(width 0.1)
				(type default)
			)
			(layer "B.Fab")
		)
		(fp_line
			(start 0.12065 -0.2794)
			(end -0.12065 -0.2794)
			(stroke
				(width 0.1)
				(type default)
			)
			(layer "B.Fab")
		)
		(fp_line
			(start 0.12065 -0.305054)
			(end 0.12065 -0.2794)
			(stroke
				(width 0.1)
				(type default)
			)
			(layer "B.Fab")
		)
		(fp_line
			(start -0.120396 0.3048)
			(end -0.120396 0.2794)
			(stroke
				(width 0.1)
				(type default)
			)
			(layer "B.Fab")
		)
		(fp_line
			(start -0.120396 0.2794)
			(end 0.12065 0.2794)
			(stroke
				(width 0.1)
				(type default)
			)
			(layer "B.Fab")
		)
		(fp_line
			(start -0.12065 -0.2794)
			(end -0.12065 -0.3048)
			(stroke
				(width 0.1)
				(type default)
			)
			(layer "B.Fab")
		)
		(fp_line
			(start -0.12065 -0.3048)
			(end -0.67945 -0.3048)
			(stroke
				(width 0.1)
				(type default)
			)
			(layer "B.Fab")
		)
		(fp_line
			(start -0.67945 0.3048)
			(end -0.120396 0.3048)
			(stroke
				(width 0.1)
				(type default)
			)
			(layer "B.Fab")
		)
		(fp_line
			(start -0.67945 -0.3048)
			(end -0.67945 0.3048)
			(stroke
				(width 0.1)
				(type default)
			)
			(layer "B.Fab")
		)
		(pad "1" smd circle
			(at 0.40005 0)
			(size 0 0)
			(layers "B.Cu" "B.Mask" "B.Paste")
			(net "FM_SWB_PWRGD_ISO")
		)
		(pad "2" smd circle
			(at -0.40005 0)
			(size 0 0)
			(layers "B.Cu" "B.Mask" "B.Paste")
			(net "GND")
		)
	)
	(footprint ""
		(layer "B.Cu")
		(at 362.265976 -256.012188 -90)
		(property "Reference" "C2543"
			(at 0 0 90)
			(layer "B.SilkS")
			(hide yes)
			(effects
				(font
					(size 1.27 1.27)
				)
				(justify mirror)
			)
		)
		(property "Value" ""
			(at 0 0 90)
			(layer "B.Fab")
			(effects
				(font
					(size 1.27 1.27)
				)
				(justify mirror)
			)
		)
		(duplicate_pad_numbers_are_jumpers no)
		(fp_line
			(start -0.7874 0.4064)
			(end 0.7874 0.4064)
			(stroke
				(width 0.1524)
				(type default)
			)
			(layer "B.SilkS")
		)
		(fp_line
			(start 0.7874 0.4064)
			(end 0.7874 -0.4064)
			(stroke
				(width 0.1524)
				(type default)
			)
			(layer "B.SilkS")
		)
		(fp_line
			(start -0.7874 -0.4064)
			(end -0.7874 0.4064)
			(stroke
				(width 0.1524)
				(type default)
			)
			(layer "B.SilkS")
		)
		(fp_line
			(start 0.7874 -0.4064)
			(end -0.7874 -0.4064)
			(stroke
				(width 0.1524)
				(type default)
			)
			(layer "B.SilkS")
		)
		(fp_line
			(start -0.67945 0.3048)
			(end -0.120396 0.3048)
			(stroke
				(width 0.1)
				(type default)
			)
			(layer "B.Fab")
		)
		(fp_line
			(start -0.120396 0.3048)
			(end -0.120396 0.2794)
			(stroke
				(width 0.1)
				(type default)
			)
			(layer "B.Fab")
		)
		(fp_line
			(start 0.12065 0.3048)
			(end 0.67945 0.3048)
			(stroke
				(width 0.1)
				(type default)
			)
			(layer "B.Fab")
		)
		(fp_line
			(start 0.67945 0.3048)
			(end 0.67945 -0.305054)
			(stroke
				(width 0.1)
				(type default)
			)
			(layer "B.Fab")
		)
		(fp_line
			(start -0.120396 0.2794)
			(end 0.12065 0.2794)
			(stroke
				(width 0.1)
				(type default)
			)
			(layer "B.Fab")
		)
		(fp_line
			(start 0.12065 0.2794)
			(end 0.12065 0.3048)
			(stroke
				(width 0.1)
				(type default)
			)
			(layer "B.Fab")
		)
		(fp_line
			(start -0.12065 -0.2794)
			(end -0.12065 -0.3048)
			(stroke
				(width 0.1)
				(type default)
			)
			(layer "B.Fab")
		)
		(fp_line
			(start 0.12065 -0.2794)
			(end -0.12065 -0.2794)
			(stroke
				(width 0.1)
				(type default)
			)
			(layer "B.Fab")
		)
		(fp_line
			(start -0.67945 -0.3048)
			(end -0.67945 0.3048)
			(stroke
				(width 0.1)
				(type default)
			)
			(layer "B.Fab")
		)
		(fp_line
			(start -0.12065 -0.3048)
			(end -0.67945 -0.3048)
			(stroke
				(width 0.1)
				(type default)
			)
			(layer "B.Fab")
		)
		(fp_line
			(start 0.12065 -0.305054)
			(end 0.12065 -0.2794)
			(stroke
				(width 0.1)
				(type default)
			)
			(layer "B.Fab")
		)
		(fp_line
			(start 0.67945 -0.305054)
			(end 0.12065 -0.305054)
			(stroke
				(width 0.1)
				(type default)
			)
			(layer "B.Fab")
		)
		(pad "1" smd circle
			(at 0.40005 0 90)
			(size 0 0)
			(layers "B.Cu" "B.Mask" "B.Paste")
			(net "PVDDCR_SOC_P0")
		)
		(pad "2" smd circle
			(at -0.40005 0 90)
			(size 0 0)
			(layers "B.Cu" "B.Mask" "B.Paste")
			(net "GND")
		)
	)
	(footprint ""
		(layer "B.Cu")
		(at 422.2115 -395.148562 90)
		(property "Reference" "C979"
			(at 0 0 90)
			(layer "B.SilkS")
			(hide yes)
			(effects
				(font
					(size 1.27 1.27)
				)
				(justify mirror)
			)
		)
		(property "Value" ""
			(at 0 0 90)
			(layer "B.Fab")
			(effects
				(font
					(size 1.27 1.27)
				)
				(justify mirror)
			)
		)
		(duplicate_pad_numbers_are_jumpers no)
		(fp_line
			(start 0.299974 -0.150114)
			(end -0.299974 -0.150114)
			(stroke
				(width 0.1)
				(type default)
			)
			(layer "B.Fab")
		)
		(fp_line
			(start -0.299974 -0.150114)
			(end -0.299974 0.150114)
			(stroke
				(width 0.1)
				(type default)
			)
			(layer "B.Fab")
		)
		(fp_line
			(start 0.299974 0.150114)
			(end 0.299974 -0.150114)
			(stroke
				(width 0.1)
				(type default)
			)
			(layer "B.Fab")
		)
		(fp_line
			(start -0.299974 0.150114)
			(end 0.299974 0.150114)
			(stroke
				(width 0.1)
				(type default)
			)
			(layer "B.Fab")
		)
		(pad "1" smd rect
			(at 0.2667 0 270)
			(size 0.3048 0.381)
			(layers "B.Cu" "B.Mask" "B.Paste")
			(net "P0V9_CPU0_RT2_2A")
		)
		(pad "2" smd rect
			(at -0.2667 0 270)
			(size 0.3048 0.381)
			(layers "B.Cu" "B.Mask" "B.Paste")
			(net "GND")
		)
	)
)
